G04 ================== begin FILE IDENTIFICATION RECORD ==================*
G04 Layout Name:  D:/<user>/Wistron_project/16369-sd/gbr/16369-sd.brd*
G04 Film Name:    BSMD*
G04 File Format:  Gerber RS274X*
G04 File Origin:  Cadence Allegro 16.5-S056*
G04 Origin Date:  Wed Mar 29 13:12:43 2017*
G04 *
G04 Layer:  VIA CLASS/PASTEMASK_BOTTOM*
G04 Layer:  PIN/PASTEMASK_BOTTOM*
G04 Layer:  PACKAGE GEOMETRY/PASTEMASK_BOTTOM*
G04 Layer:  DRAWING FORMAT/LAYER_PCB_STORY*
G04 Layer:  DRAWING FORMAT/LAYER_PAST_B*
G04 Layer:  BOARD GEOMETRY/PANEL_OUTLINE*
G04 *
G04 Offset:    (0.00 0.00)*
G04 Mirror:    No*
G04 Mode:      Positive*
G04 Rotation:  0*
G04 FullContactRelief:  No*
G04 UndefLineWidth:     6.00*
G04 ================== end FILE IDENTIFICATION RECORD ====================*
%FSLAX35Y35*MOIN*%
%IR0*IPPOS*OFA0.00000B0.00000*MIA0B0*SFA1.00000B1.00000*%
%ADD10C,.04*%
%ADD12C,.02*%
%ADD13C,.006*%
G75*
%LPD*%
G75*
G54D10*
X-5631Y5915D03*
X-4866Y709193D03*
X12000Y342400D03*
X222000Y8200D03*
X180200Y342500D03*
X489553Y2518D03*
G36*
G01X116364Y90640D02*
G02X116314I-25J-11900D01*
G01Y89940D01*
G03X116364I25J-11200D01*
G01Y90640D01*
G37*
G54D12*
G01X-351984Y-328833D02*
X-383984D01*
G01X-351984Y-344833D02*
Y-424833D01*
G01D02*
X998716D01*
G01X-355984Y-328833D02*
G02I-12000J0D01*
G01X-361134D02*
G02I-6850J0D01*
G01X-367984Y-344833D02*
Y-312833D01*
G01X-351984Y-344833D02*
X998716D01*
G01X-351984Y-380333D02*
X998716D01*
G01X211216Y-344833D02*
Y-424833D01*
G01X348716Y-344833D02*
Y-424833D01*
G01X463716Y-344833D02*
Y-424833D01*
G01X631216Y-344833D02*
Y-424833D01*
G01X801216Y-344833D02*
Y-424833D01*
G01X998716Y-344833D02*
Y-424833D01*
G01X1026716Y-328833D02*
G02I-12000J0D01*
G01X1021566D02*
G02I-6850J0D01*
G01X1014716Y-344833D02*
Y-312833D01*
G01X1030716Y-328833D02*
X998716D01*
G54D13*
G01X-322688Y-405500D02*
X-321814Y-404625D01*
X-321159Y-403167D01*
X-320722Y-401124D01*
X-321159Y-399375D01*
X-322032Y-398208D01*
X-323561Y-397333D01*
X-329456D01*
Y-414833D01*
X-322251D01*
X-320722Y-413667D01*
X-319849Y-411916D01*
X-319412Y-409875D01*
X-319849Y-407833D01*
X-321159Y-406083D01*
X-322688Y-405500D01*
X-329456D01*
G01X-309991Y-414833D02*
Y-403167D01*
G01Y-405500D02*
X-308899Y-404333D01*
X-307807Y-403458D01*
X-306279Y-403167D01*
X-305188Y-403458D01*
X-303877Y-404333D01*
G01X-294019Y-420083D02*
X-292709Y-420666D01*
X-290962Y-420083D01*
X-289871Y-418917D01*
X-288997Y-417458D01*
X-287688Y-412792D01*
X-284849Y-403167D01*
G01X-291836D02*
X-287688Y-412792D01*
G01X-268441Y-404625D02*
X-269969Y-403458D01*
X-271279Y-403167D01*
X-273026Y-403750D01*
X-274336Y-404916D01*
X-275209Y-406958D01*
X-275428Y-409000D01*
X-275209Y-411042D01*
X-274336Y-412792D01*
X-273026Y-414250D01*
X-271279Y-414833D01*
X-269751Y-414250D01*
X-268441Y-413083D01*
G01X-257709Y-406958D02*
X-250722D01*
X-251377Y-404916D01*
X-252469Y-403750D01*
X-253997Y-403167D01*
X-255526Y-403458D01*
X-256836Y-404333D01*
X-257709Y-406375D01*
X-258146Y-408125D01*
Y-409875D01*
X-257709Y-411625D01*
X-256617Y-413375D01*
X-255307Y-414541D01*
X-253779Y-414833D01*
X-252251Y-414250D01*
X-250722Y-412500D01*
G01X-214631Y-398792D02*
X-215941Y-397916D01*
X-217469Y-397333D01*
X-219216D01*
X-221181Y-398208D01*
X-222709Y-399666D01*
X-223801Y-401417D01*
X-224674Y-404333D01*
X-224893Y-406958D01*
X-224456Y-409583D01*
X-223801Y-411333D01*
X-222491Y-413083D01*
X-220962Y-414250D01*
X-219434Y-414833D01*
X-217906D01*
X-216377Y-414250D01*
X-215067Y-413375D01*
X-213975Y-412209D01*
G01X-198004Y-414833D02*
Y-403167D01*
G01Y-405208D02*
X-198877Y-404042D01*
X-200188Y-403458D01*
X-201716Y-403167D01*
X-203244Y-403750D01*
X-204554Y-404916D01*
X-205428Y-406666D01*
X-205864Y-409000D01*
X-205428Y-411333D01*
X-204554Y-413083D01*
X-203244Y-414250D01*
X-201716Y-414833D01*
X-200188Y-414541D01*
X-198877Y-413667D01*
X-198004Y-412500D01*
G01X-188146Y-414833D02*
Y-403167D01*
G01Y-406083D02*
X-187272Y-404625D01*
X-185962Y-403458D01*
X-184216Y-403167D01*
X-182688Y-403458D01*
X-181377Y-404625D01*
X-180722Y-406666D01*
Y-414833D01*
G01X-171519Y-420083D02*
X-170209Y-420666D01*
X-168462Y-420083D01*
X-167371Y-418917D01*
X-166497Y-417458D01*
X-165188Y-412792D01*
X-162349Y-403167D01*
G01X-169336D02*
X-165188Y-412792D01*
G01X-149434Y-414833D02*
X-150744Y-414541D01*
X-152054Y-413375D01*
X-152928Y-411333D01*
X-153364Y-409000D01*
X-152928Y-406666D01*
X-152054Y-404625D01*
X-150744Y-403458D01*
X-149434Y-403167D01*
X-148124Y-403458D01*
X-146814Y-404625D01*
X-145941Y-406666D01*
X-145722Y-409000D01*
X-145941Y-411333D01*
X-146814Y-413375D01*
X-148124Y-414541D01*
X-149434Y-414833D01*
G01X-135646D02*
Y-403167D01*
G01Y-406083D02*
X-134772Y-404625D01*
X-133462Y-403458D01*
X-131716Y-403167D01*
X-130188Y-403458D01*
X-128877Y-404625D01*
X-128222Y-406666D01*
Y-414833D01*
G01X-101082D02*
Y-397333D01*
X-92786D01*
G01X-95842Y-405791D02*
X-101082D01*
G01X-82491Y-414833D02*
Y-403167D01*
G01Y-405500D02*
X-81399Y-404333D01*
X-80307Y-403458D01*
X-78779Y-403167D01*
X-77688Y-403458D01*
X-76377Y-404333D01*
G01X-61934Y-414833D02*
X-63244Y-414541D01*
X-64554Y-413375D01*
X-65428Y-411333D01*
X-65864Y-409000D01*
X-65428Y-406666D01*
X-64554Y-404625D01*
X-63244Y-403458D01*
X-61934Y-403167D01*
X-60624Y-403458D01*
X-59314Y-404625D01*
X-58441Y-406666D01*
X-58222Y-409000D01*
X-58441Y-411333D01*
X-59314Y-413375D01*
X-60624Y-414541D01*
X-61934Y-414833D01*
G01X-48146D02*
Y-403167D01*
G01Y-406083D02*
X-47272Y-404625D01*
X-45962Y-403458D01*
X-44216Y-403167D01*
X-42688Y-403458D01*
X-41377Y-404625D01*
X-40722Y-406666D01*
Y-414833D01*
G01X-26934Y-397333D02*
Y-414833D01*
G01X-29991Y-403167D02*
X-23877D01*
G01X3699Y-414833D02*
Y-397333D01*
X8939D01*
X10686Y-398208D01*
X11996Y-400250D01*
X12433Y-402583D01*
X11996Y-404916D01*
X10904Y-406666D01*
X8939Y-407542D01*
X3699D01*
G01X29496Y-414833D02*
Y-403167D01*
G01Y-405208D02*
X28623Y-404042D01*
X27312Y-403458D01*
X25784Y-403167D01*
X24256Y-403750D01*
X22946Y-404916D01*
X22072Y-406666D01*
X21636Y-409000D01*
X22072Y-411333D01*
X22946Y-413083D01*
X24256Y-414250D01*
X25784Y-414833D01*
X27312Y-414541D01*
X28623Y-413667D01*
X29496Y-412500D01*
G01X39354Y-414833D02*
Y-403167D01*
G01Y-406083D02*
X40228Y-404625D01*
X41538Y-403458D01*
X43284Y-403167D01*
X44812Y-403458D01*
X46123Y-404625D01*
X46778Y-406666D01*
Y-414833D01*
G01X57291Y-406958D02*
X64278D01*
X63623Y-404916D01*
X62531Y-403750D01*
X61003Y-403167D01*
X59474Y-403458D01*
X58164Y-404333D01*
X57291Y-406375D01*
X56854Y-408125D01*
Y-409875D01*
X57291Y-411625D01*
X58383Y-413375D01*
X59693Y-414541D01*
X61221Y-414833D01*
X62749Y-414250D01*
X64278Y-412500D01*
G01X78066Y-414833D02*
Y-397333D01*
G01X114812Y-405500D02*
X115686Y-404625D01*
X116341Y-403167D01*
X116778Y-401124D01*
X116341Y-399375D01*
X115468Y-398208D01*
X113939Y-397333D01*
X108044D01*
Y-414833D01*
X115249D01*
X116778Y-413667D01*
X117651Y-411916D01*
X118088Y-409875D01*
X117651Y-407833D01*
X116341Y-406083D01*
X114812Y-405500D01*
X108044D01*
G01X130566Y-414833D02*
X129256Y-414541D01*
X127946Y-413375D01*
X127072Y-411333D01*
X126636Y-409000D01*
X127072Y-406666D01*
X127946Y-404625D01*
X129256Y-403458D01*
X130566Y-403167D01*
X131876Y-403458D01*
X133186Y-404625D01*
X134059Y-406666D01*
X134278Y-409000D01*
X134059Y-411333D01*
X133186Y-413375D01*
X131876Y-414541D01*
X130566Y-414833D01*
G01X151996D02*
Y-403167D01*
G01Y-405208D02*
X151123Y-404042D01*
X149812Y-403458D01*
X148284Y-403167D01*
X146756Y-403750D01*
X145446Y-404916D01*
X144572Y-406666D01*
X144136Y-409000D01*
X144572Y-411333D01*
X145446Y-413083D01*
X146756Y-414250D01*
X148284Y-414833D01*
X149812Y-414541D01*
X151123Y-413667D01*
X151996Y-412500D01*
G01X162509Y-414833D02*
Y-403167D01*
G01Y-405500D02*
X163601Y-404333D01*
X164693Y-403458D01*
X166221Y-403167D01*
X167312Y-403458D01*
X168623Y-404333D01*
G01X186996Y-397333D02*
Y-414833D01*
G01Y-412209D02*
X186123Y-413667D01*
X184812Y-414541D01*
X183284Y-414833D01*
X181538Y-414250D01*
X180228Y-412792D01*
X179354Y-411042D01*
X179136Y-409000D01*
X179354Y-406958D01*
X180228Y-405208D01*
X181538Y-403750D01*
X183284Y-403167D01*
X184812Y-403458D01*
X185904Y-404042D01*
X186996Y-405208D01*
G01X-111361Y-369833D02*
Y-352333D01*
X-105684Y-366916D01*
X-100007Y-352333D01*
Y-369833D01*
G01X-88184D02*
X-89494Y-369541D01*
X-90804Y-368375D01*
X-91678Y-366333D01*
X-92114Y-364000D01*
X-91678Y-361666D01*
X-90804Y-359625D01*
X-89494Y-358458D01*
X-88184Y-358167D01*
X-86874Y-358458D01*
X-85564Y-359625D01*
X-84691Y-361666D01*
X-84472Y-364000D01*
X-84691Y-366333D01*
X-85564Y-368375D01*
X-86874Y-369541D01*
X-88184Y-369833D01*
G01X-66754Y-352333D02*
Y-369833D01*
G01Y-367209D02*
X-67627Y-368667D01*
X-68938Y-369541D01*
X-70466Y-369833D01*
X-72212Y-369250D01*
X-73522Y-367792D01*
X-74396Y-366042D01*
X-74614Y-364000D01*
X-74396Y-361958D01*
X-73522Y-360208D01*
X-72212Y-358750D01*
X-70466Y-358167D01*
X-68938Y-358458D01*
X-67846Y-359042D01*
X-66754Y-360208D01*
G01X-56459Y-361958D02*
X-49472D01*
X-50127Y-359916D01*
X-51219Y-358750D01*
X-52747Y-358167D01*
X-54276Y-358458D01*
X-55586Y-359333D01*
X-56459Y-361375D01*
X-56896Y-363125D01*
Y-364875D01*
X-56459Y-366625D01*
X-55367Y-368375D01*
X-54057Y-369541D01*
X-52529Y-369833D01*
X-51001Y-369250D01*
X-49472Y-367500D01*
G01X-35684Y-369833D02*
Y-352333D01*
G01X244916Y-414833D02*
Y-397333D01*
X242296Y-400833D01*
G01Y-414833D02*
X247536D01*
G01X258268Y-407542D02*
X259796Y-405500D01*
X261106Y-404333D01*
X262853Y-403750D01*
X264381Y-404333D01*
X265473Y-405500D01*
X266346Y-407250D01*
X266564Y-409291D01*
X266346Y-411042D01*
X265473Y-412792D01*
X264162Y-414250D01*
X262634Y-414833D01*
X260888Y-414250D01*
X259359Y-412500D01*
X258486Y-409875D01*
X258268Y-406958D01*
X258704Y-403167D01*
X259359Y-401124D01*
X260451Y-399083D01*
X261979Y-397625D01*
X263508Y-397333D01*
X265036Y-397916D01*
X266128Y-399375D01*
G01X275113Y-411333D02*
X276422Y-413375D01*
X278169Y-414541D01*
X280134Y-414833D01*
X281881Y-414541D01*
X283628Y-413083D01*
X284719Y-411333D01*
X284938Y-409583D01*
X284501Y-407542D01*
X282973Y-406083D01*
X281444Y-405500D01*
X279479D01*
G01X281444D02*
X282754Y-404625D01*
X283846Y-403167D01*
X284283Y-401417D01*
X283846Y-399666D01*
X282754Y-398208D01*
X280789Y-397333D01*
X278824Y-397625D01*
X276859Y-398792D01*
G01X293268Y-407542D02*
X294796Y-405500D01*
X296106Y-404333D01*
X297853Y-403750D01*
X299381Y-404333D01*
X300473Y-405500D01*
X301346Y-407250D01*
X301564Y-409291D01*
X301346Y-411042D01*
X300473Y-412792D01*
X299162Y-414250D01*
X297634Y-414833D01*
X295888Y-414250D01*
X294359Y-412500D01*
X293486Y-409875D01*
X293268Y-406958D01*
X293704Y-403167D01*
X294359Y-401124D01*
X295451Y-399083D01*
X296979Y-397625D01*
X298508Y-397333D01*
X300036Y-397916D01*
X301128Y-399375D01*
G01X311204Y-412792D02*
X312733Y-414250D01*
X314479Y-414833D01*
X316226Y-414250D01*
X317754Y-412500D01*
X318846Y-409875D01*
X319283Y-407250D01*
Y-404042D01*
X318846Y-401417D01*
X317754Y-399083D01*
X316444Y-397916D01*
X314916Y-397333D01*
X313169Y-397916D01*
X311859Y-399083D01*
X310986Y-400833D01*
X310549Y-403167D01*
X310986Y-405208D01*
X312078Y-407250D01*
X313388Y-408417D01*
X314916Y-408708D01*
X316662Y-408125D01*
X317973Y-406666D01*
X319283Y-404042D01*
G01X231799Y-369833D02*
Y-352333D01*
X237039D01*
X238786Y-353208D01*
X240096Y-355250D01*
X240533Y-357583D01*
X240096Y-359916D01*
X239004Y-361666D01*
X237039Y-362542D01*
X231799D01*
G01X258469Y-353792D02*
X257159Y-352916D01*
X255631Y-352333D01*
X253884D01*
X251919Y-353208D01*
X250391Y-354666D01*
X249299Y-356417D01*
X248426Y-359333D01*
X248207Y-361958D01*
X248644Y-364583D01*
X249299Y-366333D01*
X250609Y-368083D01*
X252138Y-369250D01*
X253666Y-369833D01*
X255194D01*
X256723Y-369250D01*
X258033Y-368375D01*
X259125Y-367209D01*
G01X272912Y-360500D02*
X273786Y-359625D01*
X274441Y-358167D01*
X274878Y-356124D01*
X274441Y-354375D01*
X273568Y-353208D01*
X272039Y-352333D01*
X266144D01*
Y-369833D01*
X273349D01*
X274878Y-368667D01*
X275751Y-366916D01*
X276188Y-364875D01*
X275751Y-362833D01*
X274441Y-361083D01*
X272912Y-360500D01*
X266144D01*
G01X282116Y-375666D02*
X295216D01*
G01X301144Y-369833D02*
Y-352333D01*
X311188Y-369833D01*
Y-352333D01*
G01X323666Y-369833D02*
X321919Y-369541D01*
X320391Y-368375D01*
X319081Y-366625D01*
X318207Y-364583D01*
X317771Y-362250D01*
Y-359916D01*
X318207Y-357583D01*
X319081Y-355541D01*
X320391Y-353792D01*
X321919Y-352625D01*
X323666Y-352333D01*
X325412Y-352625D01*
X326941Y-353792D01*
X328251Y-355541D01*
X329125Y-357583D01*
X329561Y-359916D01*
Y-362250D01*
X329125Y-364583D01*
X328251Y-366625D01*
X326941Y-368375D01*
X325412Y-369541D01*
X323666Y-369833D01*
G01X374507Y-352333D02*
X379966Y-369833D01*
X385425Y-352333D01*
G01X401833Y-369833D02*
X393099D01*
Y-352333D01*
X401833D01*
G01X398339Y-360791D02*
X393099D01*
G01X410599Y-369833D02*
Y-352333D01*
X416058D01*
X417804Y-353208D01*
X418896Y-354375D01*
X419333Y-356708D01*
X418896Y-359042D01*
X417586Y-360500D01*
X416058Y-361375D01*
X410599D01*
G01X416058D02*
X419333Y-369833D01*
G01X432466Y-370416D02*
X432029Y-370125D01*
Y-369541D01*
X432466Y-369250D01*
X432903Y-369541D01*
Y-370125D01*
X432466Y-370416D01*
G01X392881Y-412500D02*
X394628Y-413958D01*
X396593Y-414833D01*
X398339D01*
X400086Y-413958D01*
X401396Y-412500D01*
X402051Y-410458D01*
X401614Y-408417D01*
X400523Y-406666D01*
X398558Y-405500D01*
X395938Y-404916D01*
X394409Y-403750D01*
X393754Y-401708D01*
X394191Y-399666D01*
X395283Y-398208D01*
X396811Y-397333D01*
X398339D01*
X399868Y-397916D01*
X401178Y-399375D01*
G01X410163Y-414833D02*
Y-397333D01*
X414529D01*
X416276Y-398208D01*
X417586Y-399375D01*
X418678Y-401124D01*
X419551Y-403167D01*
X419769Y-406083D01*
X419551Y-409000D01*
X418678Y-411042D01*
X417586Y-412792D01*
X416276Y-413958D01*
X414529Y-414833D01*
X410163D01*
G01X571920Y-405500D02*
X571046Y-404625D01*
X570391Y-403167D01*
X569954Y-401124D01*
X570391Y-399375D01*
X571264Y-398208D01*
X572793Y-397333D01*
X578688D01*
Y-414833D01*
X571483D01*
X569954Y-413667D01*
X569081Y-411916D01*
X568644Y-409875D01*
X569081Y-407833D01*
X570391Y-406083D01*
X571920Y-405500D01*
X578688D01*
G01X560751Y-412500D02*
X559004Y-413958D01*
X557039Y-414833D01*
X555293D01*
X553546Y-413958D01*
X552236Y-412500D01*
X551581Y-410458D01*
X552018Y-408417D01*
X553109Y-406666D01*
X555074Y-405500D01*
X557694Y-404916D01*
X559223Y-403750D01*
X559878Y-401708D01*
X559441Y-399666D01*
X558349Y-398208D01*
X556821Y-397333D01*
X555293D01*
X553764Y-397916D01*
X552454Y-399375D01*
G01X544343Y-414833D02*
Y-397333D01*
X538666Y-411916D01*
X532989Y-397333D01*
Y-414833D01*
G01X525969D02*
Y-397333D01*
X521603D01*
X519856Y-398208D01*
X518546Y-399375D01*
X517454Y-401124D01*
X516581Y-403167D01*
X516363Y-406083D01*
X516581Y-409000D01*
X517454Y-411042D01*
X518546Y-412792D01*
X519856Y-413958D01*
X521603Y-414833D01*
X525969D01*
G01X508049Y-352333D02*
Y-369833D01*
X516783D01*
G01X533846D02*
Y-358167D01*
G01Y-360208D02*
X532973Y-359042D01*
X531662Y-358458D01*
X530134Y-358167D01*
X528606Y-358750D01*
X527296Y-359916D01*
X526422Y-361666D01*
X525986Y-364000D01*
X526422Y-366333D01*
X527296Y-368083D01*
X528606Y-369250D01*
X530134Y-369833D01*
X531662Y-369541D01*
X532973Y-368667D01*
X533846Y-367500D01*
G01X542831Y-375083D02*
X544141Y-375666D01*
X545888Y-375083D01*
X546979Y-373917D01*
X547853Y-372458D01*
X549162Y-367792D01*
X552001Y-358167D01*
G01X545014D02*
X549162Y-367792D01*
G01X561641Y-361958D02*
X568628D01*
X567973Y-359916D01*
X566881Y-358750D01*
X565353Y-358167D01*
X563824Y-358458D01*
X562514Y-359333D01*
X561641Y-361375D01*
X561204Y-363125D01*
Y-364875D01*
X561641Y-366625D01*
X562733Y-368375D01*
X564043Y-369541D01*
X565571Y-369833D01*
X567099Y-369250D01*
X568628Y-367500D01*
G01X579359Y-369833D02*
Y-358167D01*
G01Y-360500D02*
X580451Y-359333D01*
X581543Y-358458D01*
X583071Y-358167D01*
X584162Y-358458D01*
X585473Y-359333D01*
G01X672466Y-414833D02*
X670719Y-414541D01*
X669191Y-413375D01*
X667881Y-411625D01*
X667007Y-409583D01*
X666571Y-407250D01*
Y-404916D01*
X667007Y-402583D01*
X667881Y-400541D01*
X669191Y-398792D01*
X670719Y-397625D01*
X672466Y-397333D01*
X674212Y-397625D01*
X675741Y-398792D01*
X677051Y-400541D01*
X677925Y-402583D01*
X678361Y-404916D01*
Y-407250D01*
X677925Y-409583D01*
X677051Y-411625D01*
X675741Y-413375D01*
X674212Y-414541D01*
X672466Y-414833D01*
G01X674212Y-410166D02*
X676833Y-414833D01*
G01X685163Y-397333D02*
Y-409875D01*
X686036Y-412500D01*
X687783Y-414250D01*
X689966Y-414833D01*
X692149Y-414250D01*
X693896Y-412500D01*
X694769Y-409875D01*
Y-397333D01*
G01X704846D02*
X710086D01*
G01X707466D02*
Y-414833D01*
G01X704846D02*
X710086D01*
G01X719944D02*
Y-397333D01*
X729988Y-414833D01*
Y-397333D01*
G01X747269Y-398792D02*
X745959Y-397916D01*
X744431Y-397333D01*
X742684D01*
X740719Y-398208D01*
X739191Y-399666D01*
X738099Y-401417D01*
X737226Y-404333D01*
X737007Y-406958D01*
X737444Y-409583D01*
X738099Y-411333D01*
X739409Y-413083D01*
X740938Y-414250D01*
X742466Y-414833D01*
X743994D01*
X745523Y-414250D01*
X746833Y-413375D01*
X747925Y-412209D01*
G01X759966Y-414833D02*
Y-406958D01*
X755599Y-397333D01*
G01X764333D02*
X759966Y-406958D01*
G01X650163Y-369833D02*
Y-352333D01*
X654529D01*
X656276Y-353208D01*
X657586Y-354375D01*
X658678Y-356124D01*
X659551Y-358167D01*
X659769Y-361083D01*
X659551Y-364000D01*
X658678Y-366042D01*
X657586Y-367792D01*
X656276Y-368958D01*
X654529Y-369833D01*
X650163D01*
G01X669191Y-361958D02*
X676178D01*
X675523Y-359916D01*
X674431Y-358750D01*
X672903Y-358167D01*
X671374Y-358458D01*
X670064Y-359333D01*
X669191Y-361375D01*
X668754Y-363125D01*
Y-364875D01*
X669191Y-366625D01*
X670283Y-368375D01*
X671593Y-369541D01*
X673121Y-369833D01*
X674649Y-369250D01*
X676178Y-367500D01*
G01X686691Y-367792D02*
X687783Y-368958D01*
X689311Y-369833D01*
X690621D01*
X691931Y-369250D01*
X692804Y-368375D01*
X693241Y-367209D01*
X693023Y-365458D01*
X692149Y-364583D01*
X688219Y-362833D01*
X687346Y-360791D01*
X687783Y-359333D01*
X688656Y-358458D01*
X689966Y-358167D01*
X691276Y-358458D01*
X692586Y-359333D01*
G01X707466Y-358167D02*
Y-369833D01*
G01Y-353500D02*
X707029Y-353208D01*
Y-352625D01*
X707466Y-352333D01*
X707903Y-352625D01*
Y-353208D01*
X707466Y-353500D01*
G01X721909Y-374208D02*
X723438Y-375375D01*
X725184Y-375666D01*
X726712Y-375375D01*
X728023Y-373917D01*
X728896Y-371875D01*
Y-358167D01*
G01Y-360500D02*
X728023Y-359333D01*
X726712Y-358458D01*
X725184Y-358167D01*
X723438Y-358750D01*
X722346Y-359916D01*
X721472Y-361958D01*
X721036Y-364000D01*
X721254Y-365750D01*
X722128Y-367792D01*
X723438Y-369250D01*
X725184Y-369833D01*
X726494Y-369541D01*
X728023Y-368375D01*
X728896Y-367209D01*
G01X738754Y-369833D02*
Y-358167D01*
G01Y-361083D02*
X739628Y-359625D01*
X740938Y-358458D01*
X742684Y-358167D01*
X744212Y-358458D01*
X745523Y-359625D01*
X746178Y-361666D01*
Y-369833D01*
G01X756691Y-361958D02*
X763678D01*
X763023Y-359916D01*
X761931Y-358750D01*
X760403Y-358167D01*
X758874Y-358458D01*
X757564Y-359333D01*
X756691Y-361375D01*
X756254Y-363125D01*
Y-364875D01*
X756691Y-366625D01*
X757783Y-368375D01*
X759093Y-369541D01*
X760621Y-369833D01*
X762149Y-369250D01*
X763678Y-367500D01*
G01X774409Y-369833D02*
Y-358167D01*
G01Y-360500D02*
X775501Y-359333D01*
X776593Y-358458D01*
X778121Y-358167D01*
X779212Y-358458D01*
X780523Y-359333D01*
G01X821166Y-397333D02*
X819419Y-397916D01*
X818109Y-399375D01*
X817236Y-401124D01*
X816581Y-403458D01*
X816363Y-406083D01*
X816581Y-408708D01*
X817236Y-411042D01*
X818109Y-412792D01*
X819419Y-414250D01*
X821166Y-414833D01*
X822912Y-414250D01*
X824223Y-412792D01*
X825096Y-411042D01*
X825751Y-408708D01*
X825969Y-406083D01*
X825751Y-403458D01*
X825096Y-401124D01*
X824223Y-399375D01*
X822912Y-397916D01*
X821166Y-397333D01*
G01X833863Y-411333D02*
X835172Y-413375D01*
X836919Y-414541D01*
X838884Y-414833D01*
X840631Y-414541D01*
X842378Y-413083D01*
X843469Y-411333D01*
X843688Y-409583D01*
X843251Y-407542D01*
X841723Y-406083D01*
X840194Y-405500D01*
X838229D01*
G01X840194D02*
X841504Y-404625D01*
X842596Y-403167D01*
X843033Y-401417D01*
X842596Y-399666D01*
X841504Y-398208D01*
X839539Y-397333D01*
X837574Y-397625D01*
X835609Y-398792D01*
G01X852236Y-415416D02*
X860096Y-397333D01*
G01X869518Y-400250D02*
X870828Y-398500D01*
X872356Y-397625D01*
X874103Y-397333D01*
X876286Y-397916D01*
X877814Y-399375D01*
X878251Y-401124D01*
X878033Y-402875D01*
X877159Y-404333D01*
X872793Y-407250D01*
X870828Y-409291D01*
X869518Y-412209D01*
X869081Y-414833D01*
X878251D01*
G01X887454Y-412792D02*
X888983Y-414250D01*
X890729Y-414833D01*
X892476Y-414250D01*
X894004Y-412500D01*
X895096Y-409875D01*
X895533Y-407250D01*
Y-404042D01*
X895096Y-401417D01*
X894004Y-399083D01*
X892694Y-397916D01*
X891166Y-397333D01*
X889419Y-397916D01*
X888109Y-399083D01*
X887236Y-400833D01*
X886799Y-403167D01*
X887236Y-405208D01*
X888328Y-407250D01*
X889638Y-408417D01*
X891166Y-408708D01*
X892912Y-408125D01*
X894223Y-406666D01*
X895533Y-404042D01*
G01X904736Y-415416D02*
X912596Y-397333D01*
G01X922018Y-400250D02*
X923328Y-398500D01*
X924856Y-397625D01*
X926603Y-397333D01*
X928786Y-397916D01*
X930314Y-399375D01*
X930751Y-401124D01*
X930533Y-402875D01*
X929659Y-404333D01*
X925293Y-407250D01*
X923328Y-409291D01*
X922018Y-412209D01*
X921581Y-414833D01*
X930751D01*
G01X943666Y-397333D02*
X941919Y-397916D01*
X940609Y-399375D01*
X939736Y-401124D01*
X939081Y-403458D01*
X938863Y-406083D01*
X939081Y-408708D01*
X939736Y-411042D01*
X940609Y-412792D01*
X941919Y-414250D01*
X943666Y-414833D01*
X945412Y-414250D01*
X946723Y-412792D01*
X947596Y-411042D01*
X948251Y-408708D01*
X948469Y-406083D01*
X948251Y-403458D01*
X947596Y-401124D01*
X946723Y-399375D01*
X945412Y-397916D01*
X943666Y-397333D01*
G01X961166Y-414833D02*
Y-397333D01*
X958546Y-400833D01*
G01Y-414833D02*
X963786D01*
G01X978229D02*
X978666Y-411042D01*
X979321Y-407833D01*
X980194Y-404916D01*
X981286Y-401708D01*
X983033Y-397333D01*
X974299D01*
G01X868863Y-369833D02*
Y-352333D01*
X873229D01*
X874976Y-353208D01*
X876286Y-354375D01*
X877378Y-356124D01*
X878251Y-358167D01*
X878469Y-361083D01*
X878251Y-364000D01*
X877378Y-366042D01*
X876286Y-367792D01*
X874976Y-368958D01*
X873229Y-369833D01*
X868863D01*
G01X895096D02*
Y-358167D01*
G01Y-360208D02*
X894223Y-359042D01*
X892912Y-358458D01*
X891384Y-358167D01*
X889856Y-358750D01*
X888546Y-359916D01*
X887672Y-361666D01*
X887236Y-364000D01*
X887672Y-366333D01*
X888546Y-368083D01*
X889856Y-369250D01*
X891384Y-369833D01*
X892912Y-369541D01*
X894223Y-368667D01*
X895096Y-367500D01*
G01X908666Y-352333D02*
Y-369833D01*
G01X905609Y-358167D02*
X911723D01*
G01X922891Y-361958D02*
X929878D01*
X929223Y-359916D01*
X928131Y-358750D01*
X926603Y-358167D01*
X925074Y-358458D01*
X923764Y-359333D01*
X922891Y-361375D01*
X922454Y-363125D01*
Y-364875D01*
X922891Y-366625D01*
X923983Y-368375D01*
X925293Y-369541D01*
X926821Y-369833D01*
X928349Y-369250D01*
X929878Y-367500D01*
G01X-11811Y-26378D02*
G03X-7874Y-22441I0J3937D01*
G01X-31496Y-11378D02*
G03X-16496Y-26378I15000J0D01*
G01X0Y-18504D02*
G03X-7874I-3937J0D01*
G01X-11811Y-26378D02*
X-16496D01*
G01X-31496Y727913D02*
Y-11378D01*
G01X-7874Y-18504D02*
Y-22441D01*
G01Y20866D02*
G03X0I3937J0D01*
G01X-14607Y16741D02*
G03I-4291J0D01*
G01X-7874Y175427D02*
Y20866D01*
G01X-11608Y217029D02*
G03X-19685Y205824I3734J-11205D01*
G01X-9118Y209559D02*
G03X-11811Y205824I1244J-3735D01*
G01X-19685Y187877D02*
G03X-11608Y176672I11811J0D01*
G01X-11811Y187877D02*
G03X-9118Y184142I3937J0D01*
G01X-7874Y175427D02*
X-11609Y176672D01*
G01X-2692Y182000D02*
X-9119Y184142D01*
G01X-7874Y218273D02*
X-11609Y217029D01*
G01X-2692Y211701D02*
X-9119Y209559D01*
G01X-7874Y307086D02*
Y218273D01*
G01X-19685Y205824D02*
Y187877D01*
G01X-11811Y205824D02*
Y187877D01*
G01X0Y370079D02*
G03X-7874I-3937J0D01*
G01Y346456D02*
G03X0I3937J0D01*
G01Y307086D02*
G03X-7874I-3937J0D01*
G01Y370079D02*
Y346456D01*
G01Y409449D02*
G03X0I3937J0D01*
G01X-7874Y564010D02*
Y409449D01*
G01X-11608Y605612D02*
G03X-19685Y594406I3735J-11206D01*
G01X-9118Y598141D02*
G03X-11811Y594406I1244J-3735D01*
G01X-19685Y576459D02*
G03X-11608Y565254I11811J0D01*
G01X-11811Y576459D02*
G03X-9118Y572724I3937J0D01*
G01X-7874Y564010D02*
X-11609Y565255D01*
G01X-2692Y570582D02*
X-9119Y572725D01*
G01X-2692Y600284D02*
X-9119Y598141D01*
G01X-19685Y594406D02*
Y576459D01*
G01X-11811Y594406D02*
Y576459D01*
G01X-7874Y606856D02*
X-11609Y605611D01*
G01X-7874Y695669D02*
Y606856D01*
G01X-13215Y723144D02*
G03I-4291J0D01*
G01X-7874Y738976D02*
G03X-11811Y742913I-3937J0D01*
G01X-16496D02*
G03X-31496Y727913I0J-15000D01*
G01X-7874Y735039D02*
G03X0I3937J0D01*
G01Y695669D02*
G03X-7874I-3937J0D01*
G01X-11811Y742913D02*
X-16496D01*
G01X-7874Y738976D02*
Y735039D01*
G01X29075Y-26378D02*
G03X31044Y-24410I0J1969D01*
G01D02*
Y-788D01*
G01X0Y-22441D02*
G03X3937Y-26378I3937J0D01*
G01X0Y178265D02*
Y-22441D01*
G01X3937Y-26378D02*
X29075D01*
G01X44390Y5118D02*
G03I-2658J0D01*
G01X33012Y1181D02*
G03X31044Y-788I0J-1968D01*
G01X33012Y1181D02*
X199666D01*
G01X71407Y128987D02*
G03X76975Y134555I2784J2784D01*
G01X64567Y137457D02*
G03X65720Y134673I3938J0D01*
G01D02*
X94910Y105484D01*
G01X64567Y137457D02*
Y249131D01*
G01X-2692Y211701D02*
G03X0Y215436I-1245J3735D01*
G01Y178265D02*
G03X-2692Y182000I-3937J0D01*
G01X0Y350394D02*
Y215436D01*
G01X64567Y286302D02*
G03X67259Y282567I3937J0D01*
G01Y252866D02*
G03X64567Y249131I1245J-3735D01*
G01X73686Y280425D02*
X67259Y282567D01*
G01X64567Y286302D02*
Y350394D01*
G01X73686Y255008D02*
X67259Y252866D01*
G01X64567Y346456D02*
G03X72441I3937J0D01*
G01Y321260D02*
G03X64567I-3937J0D01*
G01X29075Y362205D02*
G03X31044Y364173I0J1969D01*
G01X0Y366142D02*
G03X3937Y362205I3937J0D01*
G01X31044Y364173D02*
Y387795D01*
G01X0Y566847D02*
Y366142D01*
G01X3937Y362205D02*
X29075D01*
G01X64567Y350394D02*
G03X60630Y354331I-3937J0D01*
G01X3937D02*
G03X0Y350394I0J-3937D01*
G01X60630Y354331D02*
X3937D01*
G01X44390Y393701D02*
G03I-2658J0D01*
G01X33012Y389764D02*
G03X31044Y387795I0J-1968D01*
G01X33012Y389764D02*
X199666D01*
G01X71407Y517570D02*
G03X76975Y523137I2784J2784D01*
G01X64567Y526040D02*
G03X65720Y523256I3938J0D01*
G01D02*
X94910Y494066D01*
G01X64567Y526040D02*
Y637713D01*
G01X-2692Y600283D02*
G03X0Y604019I-1245J3735D01*
G01Y566847D02*
G03X-2692Y570582I-3937J0D01*
G01X64567Y674885D02*
G03X67259Y671150I3937J0D01*
G01Y641448D02*
G03X64567Y637713I1245J-3735D01*
G01X73686Y669007D02*
X67259Y671150D01*
G01X64567Y674885D02*
Y738976D01*
G01X73686Y643591D02*
X67259Y641448D01*
G01X0Y738976D02*
Y604019D01*
G01X64567Y735039D02*
G03X72441I3937J0D01*
G01Y709842D02*
G03X64567I-3937J0D01*
G01Y738976D02*
G03X60630Y742913I-3937J0D01*
G01X3937D02*
G03X0Y738976I0J-3937D01*
G01X60630Y742913D02*
X3937D01*
G01X127362Y78740D02*
G03I-11023J0D01*
G01X118788Y137176D02*
G03I-4291J0D01*
G01X94791Y116738D02*
G03X89224Y111170I-2784J-2784D01*
G01X143454D02*
G03X137886Y116738I-2784J2784D01*
G01X134984Y104331D02*
G03X137768Y105484I0J3938D01*
G01X94910D02*
G03X97694Y104331I2784J2785D01*
G01X137886Y116738D02*
X133353Y112205D01*
G01X166957Y134673D02*
X137768Y105484D01*
G01X94791Y116738D02*
X99325Y112205D01*
G01X72441Y139088D02*
X76975Y134555D01*
G01X72441Y139088D02*
Y246293D01*
G01X133353Y112205D02*
X99325D01*
G01X134984Y104331D02*
X97694D01*
G01X84252Y276690D02*
G03X76175Y287895I-11811J0D01*
G01X76378Y276690D02*
G03X73686Y280425I-3937J0D01*
G01X76175Y247538D02*
G03X84252Y258743I-3734J11205D01*
G01X73686Y255008D02*
G03X76378Y258743I-1245J3735D01*
G01X76176Y287895D02*
X72441Y289140D01*
G01X84252Y258743D02*
Y276690D01*
G01X76378Y258743D02*
Y276690D01*
G01X72441Y289140D02*
Y321260D01*
G01X76176Y247538D02*
X72441Y246293D01*
G01X119874Y329366D02*
G03I-4291J0D01*
G01X76378Y354331D02*
G03X72441Y350394I0J-3937D01*
G01X76378Y354331D02*
X156299D01*
G01X72441Y346456D02*
Y350394D01*
G01X118788Y525759D02*
G03I-4291J0D01*
G01X94791Y505321D02*
G03X89224Y499753I-2784J-2784D01*
G01X143454D02*
G03X137886Y505321I-2784J2784D01*
G01D02*
X133353Y500787D01*
G01X94791Y505321D02*
X99325Y500787D01*
G01X72441Y527671D02*
X76975Y523137D01*
G01X133353Y500787D02*
X99325D01*
G01X134984Y492913D02*
G03X137768Y494066I0J3938D01*
G01X127362Y467323D02*
G03I-11023J0D01*
G01X94910Y494066D02*
G03X97694Y492913I2784J2785D01*
G01X166957Y523256D02*
X137768Y494066D01*
G01X134984Y492913D02*
X97694D01*
G01X72441Y527671D02*
Y634876D01*
G01X84252Y665272D02*
G03X76175Y676478I-11812J0D01*
G01Y636120D02*
G03X84252Y647326I-3735J11206D01*
G01X76176Y676477D02*
X72441Y677722D01*
G01X84252Y647326D02*
Y665272D01*
G01X72441Y677722D02*
Y709842D01*
G01X76176Y636121D02*
X72441Y634876D01*
G01X76378Y665272D02*
G03X73686Y669007I-3937J0D01*
G01Y643591D02*
G03X76378Y647326I-1245J3735D01*
G01D02*
Y665272D01*
G01X119874Y717948D02*
G03I-4291J0D01*
G01X76378Y742913D02*
G03X72441Y738976I0J-3937D01*
G01X76378Y742913D02*
X156299D01*
G01X72441Y735039D02*
Y738976D01*
G01X201634Y-24410D02*
G03X203603Y-26378I1968J0D01*
G01X201634Y-788D02*
Y-24410D01*
G01X203603Y-26378D02*
X228740D01*
G01X193603Y5118D02*
G03I-2658J0D01*
G01X201634Y-788D02*
G03X199666Y1181I-1969J0D01*
G01X155703Y134555D02*
G03X161271Y128987I2784J-2784D01*
G01X166957Y134673D02*
G03X168110Y137457I-2785J2784D01*
G01X160236Y139088D02*
X155703Y134555D01*
G01X160236Y246293D02*
Y139088D01*
G01X168110Y249131D02*
Y137457D01*
G01X165418Y282567D02*
G03X168110Y286302I-1245J3735D01*
G01X156502Y287895D02*
G03X148425Y276690I3734J-11205D01*
G01X158992Y280425D02*
G03X156299Y276690I1244J-3735D01*
G01X168110Y249131D02*
G03X165418Y252866I-3937J0D01*
G01X148425Y258743D02*
G03X156502Y247538I11811J0D01*
G01X156299Y258743D02*
G03X158992Y255008I3937J0D01*
G01X160236Y246293D02*
X156501Y247538D01*
G01X165418Y252866D02*
X158991Y255008D01*
G01X160236Y321260D02*
Y289140D01*
G01X168110Y350394D02*
Y286302D01*
G01X148425Y276690D02*
Y258743D01*
G01X156299Y276690D02*
Y258743D01*
G01X160236Y289140D02*
X156501Y287895D01*
G01X165418Y282567D02*
X158991Y280425D01*
G01X225227Y362205D02*
G03Y354331I0J-3937D01*
G01X207116D02*
G03Y362205I0J3937D01*
G01X160236Y346456D02*
G03X168110I3937J0D01*
G01Y321260D02*
G03X160236I-3937J0D01*
G01Y350394D02*
G03X156299Y354331I-3937J0D01*
G01X201634Y364173D02*
G03X203603Y362205I1968J0D01*
G01X201634Y387795D02*
Y364173D01*
G01X203603Y362205D02*
X228740D01*
G01X172047Y354331D02*
G03X168110Y350394I0J-3937D01*
G01X228740Y354331D02*
X172047D01*
G01X160236Y350394D02*
Y346456D01*
G01X193603Y393701D02*
G03I-2658J0D01*
G01X201634Y387795D02*
G03X199666Y389764I-1969J0D01*
G01X155703Y523137D02*
G03X161271Y517570I2784J-2783D01*
G01X160236Y527671D02*
X155703Y523137D01*
G01X166957Y523256D02*
G03X168110Y526040I-2785J2784D01*
G01Y637713D02*
Y526040D01*
G01X160236Y634876D02*
Y527671D01*
G01X156502Y676478D02*
G03X148425Y665272I3735J-11206D01*
G01Y647326D02*
G03X156502Y636120I11812J0D01*
G01X160236Y634876D02*
X156501Y636121D01*
G01X160236Y709842D02*
Y677722D01*
G01X148425Y665272D02*
Y647326D01*
G01X160236Y677722D02*
X156501Y676477D01*
G01X165418Y671150D02*
G03X168110Y674885I-1245J3735D01*
G01X158992Y669007D02*
G03X156299Y665272I1244J-3735D01*
G01X168110Y637713D02*
G03X165418Y641448I-3937J0D01*
G01X156299Y647326D02*
G03X158992Y643591I3937J0D01*
G01X165418Y641448D02*
X158991Y643591D01*
G01X168110Y738976D02*
Y674885D01*
G01X156299Y665272D02*
Y647326D01*
G01X165418Y671150D02*
X158991Y669007D01*
G01X160236Y735039D02*
G03X168110I3937J0D01*
G01Y709842D02*
G03X160236I-3937J0D01*
G01Y738976D02*
G03X156299Y742913I-3937J0D01*
G01X160236Y738976D02*
Y735039D01*
G01X172047Y742913D02*
G03X168110Y738976I0J-3937D01*
G01X228740Y742913D02*
X172047D01*
G01X236614Y-14567D02*
X244488D01*
G01X236614D02*
G03X232677Y-18504I0J-3937D01*
G01X248425D02*
G03X244488Y-14567I-3937J0D01*
G01X248425Y-22441D02*
G03X252362Y-26378I3937J0D01*
G01D02*
X309055D01*
G01X248425Y112921D02*
Y-22441D01*
G01X228740Y-26378D02*
G03X232677Y-22441I0J3937D01*
G01D02*
Y178669D01*
G01X236614Y16929D02*
X244488D01*
G01X232677Y20866D02*
G03X236614Y16929I3937J0D01*
G01X244488D02*
G03X248425Y20866I0J3937D01*
G01X246249Y145762D02*
G03X248425Y149283I-1761J3521D01*
G01Y112921D02*
G03X246249Y116442I-3937J0D01*
G01X242727Y144001D02*
G03X240551Y140480I1761J-3521D01*
G01Y121724D02*
G03X242727Y118203I3937J0D01*
G01X240551Y140480D02*
Y121724D01*
G01X242728Y118203D02*
X246249Y116442D01*
G01X242728Y144001D02*
X246249Y145762D01*
G01X248425Y350394D02*
Y149283D01*
G01X234853Y182190D02*
G03X232677Y178669I1761J-3521D01*
G01Y215031D02*
G03X234853Y211510I3937J0D01*
G01X238375Y183951D02*
G03X240551Y187472I-1761J3521D01*
G01Y206228D02*
G03X238375Y209749I-3937J0D01*
G01X240551Y187472D02*
Y206228D01*
G01X232677Y215031D02*
Y350394D01*
G01X238375Y209749D02*
X234854Y211510D01*
G01X238375Y183951D02*
X234854Y182190D01*
G01X273986Y362205D02*
G03Y354331I0J-3937D01*
G01X255876D02*
G03Y362205I0J3937D01*
G01X236614Y374016D02*
X244488D01*
G01X236614D02*
G03X232677Y370079I0J-3937D01*
G01X248425D02*
G03X244488Y374016I-3937J0D01*
G01X236614Y342519D02*
X244488D01*
G01X236614Y311023D02*
X244488D01*
G01X236614D02*
G03X232677Y307086I0J-3937D01*
G01Y346456D02*
G03X236614Y342519I3937J0D01*
G01X244488D02*
G03X248425Y346456I0J3937D01*
G01Y307086D02*
G03X244488Y311023I-3937J0D01*
G01X248425Y366142D02*
G03X252362Y362205I3937J0D01*
G01D02*
X309055D01*
G01X248425Y501504D02*
Y366142D01*
G01X228740Y362205D02*
G03X232677Y366142I0J3937D01*
G01D02*
Y567252D01*
G01X279469Y352362D02*
G03X277500Y354331I-1969J0D01*
G01X252362D02*
G03X248425Y350394I0J-3937D01*
G01X292815Y322834D02*
G03I-2657J0D01*
G01X279469Y328740D02*
G03X281437Y326771I1969J0D01*
G01X279469Y328740D02*
Y352362D01*
G01X448091Y326771D02*
X281437D01*
G01X277500Y354331D02*
X252362D01*
G01X232677Y350394D02*
G03X228740Y354331I-3937J0D01*
G01X236614Y405512D02*
X244488D01*
G01X232677Y409449D02*
G03X236614Y405512I3937J0D01*
G01X244488D02*
G03X248425Y409449I0J3937D01*
G01Y501504D02*
G03X246249Y505025I-3937J0D01*
G01X240551Y510307D02*
G03X242727Y506786I3937J0D01*
G01X240551Y529063D02*
Y510307D01*
G01X242728Y506786D02*
X246249Y505025D01*
G01Y534345D02*
G03X248425Y537866I-1761J3521D01*
G01X242727Y532584D02*
G03X240551Y529063I1761J-3521D01*
G01X248425Y738976D02*
Y537866D01*
G01X242728Y532584D02*
X246249Y534345D01*
G01X234853Y570773D02*
G03X232677Y567252I1761J-3521D01*
G01Y603614D02*
G03X234853Y600093I3937J0D01*
G01X238375Y572534D02*
G03X240551Y576055I-1761J3521D01*
G01Y594811D02*
G03X238375Y598332I-3937J0D01*
G01X240551Y576055D02*
Y594811D01*
G01X238375Y598332D02*
X234854Y600093D01*
G01X238375Y572534D02*
X234854Y570773D01*
G01X232677Y603614D02*
Y738976D01*
G01X236614Y731102D02*
X244488D01*
G01X236614Y699606D02*
X244488D01*
G01X236614D02*
G03X232677Y695669I0J-3937D01*
G01Y735039D02*
G03X236614Y731102I3937J0D01*
G01X244488D02*
G03X248425Y735039I0J3937D01*
G01Y695669D02*
G03X244488Y699606I-3937J0D01*
G01X279469Y740945D02*
G03X277500Y742913I-1968J0D01*
G01X252362D02*
G03X248425Y738976I0J-3937D01*
G01X292815Y711417D02*
G03I-2657J0D01*
G01X279469Y717323D02*
G03X281437Y715354I1969J0D01*
G01X279469Y717323D02*
Y740945D01*
G01X448091Y715354D02*
X281437D01*
G01X277500Y742913D02*
X252362D01*
G01X232677Y738976D02*
G03X228740Y742913I-3937J0D01*
G01X369811Y-1413D02*
G03I-4291J0D01*
G01X320866Y-18504D02*
G03X312992I-3937J0D01*
G01X320866Y-22441D02*
G03X324803Y-26378I3937J0D01*
G01X404725D02*
X324803D01*
G01X320866Y-22441D02*
Y-18504D01*
G01X309055Y-26378D02*
G03X312992Y-22441I0J3937D01*
G01D02*
Y41650D01*
G01Y6693D02*
G03X320866I3937J0D01*
G01X324600Y40057D02*
G03X332677Y51263I-3735J11206D01*
G01Y69209D02*
G03X324600Y80415I-11812J0D01*
G01X320866Y6693D02*
Y38813D01*
G01X332677Y51263D02*
Y69209D01*
G01X320866Y38813D02*
X324601Y40058D01*
G01X315685Y45385D02*
G03X312992Y41650I1244J-3735D01*
G01X322111Y47528D02*
G03X324803Y51263I-1245J3735D01*
G01Y69209D02*
G03X322111Y72944I-3937J0D01*
G01X324803Y51263D02*
Y69209D01*
G01X315684Y45385D02*
X322111Y47528D01*
G01X320866Y81659D02*
X324601Y80414D01*
G01X320866Y81659D02*
Y188864D01*
G01X312992Y78822D02*
G03X315685Y75087I3937J0D01*
G01X315684D02*
X322111Y72944D01*
G01X312992Y78822D02*
Y190495D01*
G01X370897Y190776D02*
G03I-4291J0D01*
G01X337649Y216782D02*
G03X343217Y211214I2784J-2784D01*
G01X325400Y193398D02*
G03X319832Y198965I-2784J2784D01*
G01X343217Y211214D02*
X347750Y215748D01*
G01X320866Y188864D02*
X325400Y193398D01*
G01X347750Y215748D02*
X381778D01*
G01X314145Y193279D02*
G03X312992Y190495I2785J-2784D01*
G01X346119Y223622D02*
G03X343335Y222469I0J-3938D01*
G01X314145Y193279D02*
X343335Y222469D01*
G01X375788Y249212D02*
G03I-11024J0D01*
G01X346119Y223622D02*
X383409D01*
G01X320866Y370079D02*
G03X312992I-3937J0D01*
G01X320866Y366142D02*
G03X324803Y362205I3937J0D01*
G01X404725D02*
X324803D01*
G01X320866Y366142D02*
Y370079D01*
G01X309055Y362205D02*
G03X312992Y366142I0J3937D01*
G01D02*
Y430233D01*
G01X369811Y387169D02*
G03I-4291J0D01*
G01X312992Y395275D02*
G03X320866I3937J0D01*
G01X324600Y428640D02*
G03X332677Y439845I-3734J11205D01*
G01X320866Y395275D02*
Y427395D01*
G01X332677Y439845D02*
Y457792D01*
G01X320866Y427395D02*
X324601Y428640D01*
G01X315685Y433968D02*
G03X312992Y430233I1244J-3735D01*
G01X322111Y436110D02*
G03X324803Y439845I-1245J3735D01*
G01D02*
Y457792D01*
G01X315684Y433968D02*
X322111Y436110D01*
G01X332677Y457792D02*
G03X324600Y468997I-11811J0D01*
G01X320866Y470242D02*
X324601Y468997D01*
G01X320866Y470242D02*
Y577447D01*
G01X312992Y467404D02*
G03X315685Y463669I3937J0D01*
G01X324803Y457792D02*
G03X322111Y461527I-3937J0D01*
G01X315684Y463669D02*
X322111Y461527D01*
G01X312992Y467404D02*
Y579078D01*
G01X370897Y579359D02*
G03I-4291J0D01*
G01X337649Y605365D02*
G03X343217Y599797I2784J-2784D01*
G01X325400Y581980D02*
G03X319832Y587548I-2784J2784D01*
G01X343217Y599797D02*
X347750Y604331D01*
G01X320866Y577447D02*
X325400Y581980D01*
G01X314145Y581862D02*
G03X312992Y579078I2785J-2784D01*
G01X314145Y581862D02*
X343335Y611051D01*
G01X347750Y604331D02*
X381778D01*
G01X346119Y612205D02*
G03X343335Y611051I1J-3937D01*
G01X375788Y637795D02*
G03I-11024J0D01*
G01X346119Y612205D02*
X383409D01*
G01X416536Y-18504D02*
G03X408662I-3937J0D01*
G01X404725Y-26378D02*
G03X408662Y-22441I0J3937D01*
G01Y-18504D02*
Y-22441D01*
G01X416536D02*
G03X420473Y-26378I3937J0D01*
G01D02*
X477166D01*
G01X416536Y41650D02*
Y-22441D01*
G01X408662Y6693D02*
G03X416536I3937J0D01*
G01X396851Y51263D02*
G03X404928Y40057I11812J0D01*
G01Y80415D02*
G03X396851Y69209I3735J-11206D01*
G01X404927Y40058D02*
X408662Y38813D01*
G01X396851Y69209D02*
Y51263D01*
G01X408662Y38813D02*
Y6693D01*
G01X416536Y41650D02*
G03X413843Y45385I-3937J0D01*
G01X404725Y51263D02*
G03X407417Y47528I3937J0D01*
G01Y72944D02*
G03X404725Y69209I1245J-3735D01*
G01X407417Y47528D02*
X413844Y45385D01*
G01X404725Y69209D02*
Y51263D01*
G01X408662Y188864D02*
Y81659D01*
G01X404927Y80414D02*
X408662Y81659D01*
G01X413843Y75087D02*
G03X416536Y78822I-1244J3735D01*
G01Y190495D02*
Y78822D01*
G01X407417Y72944D02*
X413844Y75087D01*
G01X409696Y198965D02*
G03X404128Y193398I-2784J-2783D01*
G01X386311Y211214D02*
G03X391879Y216782I2784J2784D01*
G01X386311Y211214D02*
X381778Y215748D01*
G01X408662Y188864D02*
X404128Y193398D01*
G01X386193Y222469D02*
G03X383409Y223622I-2784J-2785D01*
G01X416536Y190495D02*
G03X415383Y193279I-3938J0D01*
G01D02*
X386193Y222469D01*
G01X416536Y370079D02*
G03X408662I-3937J0D01*
G01X404725Y362205D02*
G03X408662Y366142I0J3937D01*
G01Y370079D02*
Y366142D01*
G01X416536D02*
G03X420473Y362205I3937J0D01*
G01D02*
X477166D01*
G01X416536Y430233D02*
Y366142D01*
G01X442028Y322834D02*
G03I-2658J0D01*
G01X448091Y326771D02*
G03X450059Y328740I0J1968D01*
G01X452028Y354331D02*
G03X450059Y352362I0J-1969D01*
G01D02*
Y328740D01*
G01X408662Y395275D02*
G03X416536I3937J0D01*
G01X396851Y439845D02*
G03X404928Y428640I11811J0D01*
G01X404927D02*
X408662Y427395D01*
G01X396851Y457792D02*
Y439845D01*
G01X408662Y427395D02*
Y395275D01*
G01X416536Y430233D02*
G03X413843Y433968I-3937J0D01*
G01X404725Y439845D02*
G03X407417Y436110I3937J0D01*
G01D02*
X413844Y433968D01*
G01X404725Y457792D02*
Y439845D01*
G01X404928Y468997D02*
G03X396851Y457792I3734J-11205D01*
G01X408662Y577447D02*
Y470242D01*
G01X404927Y468997D02*
X408662Y470242D01*
G01X413843Y463669D02*
G03X416536Y467404I-1244J3735D01*
G01X407417Y461527D02*
G03X404725Y457792I1245J-3735D01*
G01X416536Y579078D02*
Y467404D01*
G01X407417Y461527D02*
X413844Y463669D01*
G01X409696Y587548D02*
G03X404128Y581980I-2784J-2784D01*
G01X386311Y599797D02*
G03X391879Y605365I2784J2784D01*
G01X386311Y599797D02*
X381778Y604331D01*
G01X408662Y577447D02*
X404128Y581980D01*
G01X416536Y579078D02*
G03X415383Y581862I-3938J0D01*
G01D02*
X386193Y611051D01*
G01D02*
G03X383409Y612205I-2785J-2783D01*
G01X442028Y711417D02*
G03I-2658J0D01*
G01X448091Y715354D02*
G03X450059Y717323I0J1968D01*
G01X452028Y742913D02*
G03X450059Y740945I0J-1969D01*
G01D02*
Y717323D01*
G01X488977Y-22441D02*
G03X492914Y-26378I3937J0D01*
G01X497599D02*
G03X512599Y-11378I0J15000D01*
G01X488977Y-18504D02*
G03X481103I-3937J0D01*
G01X492914Y-26378D02*
X497599D01*
G01X512599Y-11378D02*
Y455139D01*
G01X488977Y-22441D02*
Y-18504D01*
G01X477166Y-26378D02*
G03X481103Y-22441I0J3937D01*
G01D02*
Y112517D01*
G01Y20866D02*
G03X488977I3937J0D01*
G01D02*
Y109679D01*
G01X492711Y110924D02*
G03X500788Y122129I-3734J11205D01*
G01Y140076D02*
G03X492711Y151281I-11811J0D01*
G01X488977Y109679D02*
X492712Y110924D01*
G01X500788Y122129D02*
Y140076D01*
G01X483795Y116252D02*
G03X481103Y112517I1245J-3735D01*
G01Y149688D02*
G03X483795Y145953I3937J0D01*
G01X490221Y118394D02*
G03X492914Y122129I-1244J3735D01*
G01Y140076D02*
G03X490221Y143811I-3937J0D01*
G01X483795Y145953D02*
X490222Y143811D01*
G01X483795Y116251D02*
X490222Y118394D01*
G01X492914Y122129D02*
Y140076D01*
G01X488977Y152525D02*
X492712Y151280D01*
G01X488977Y152525D02*
Y307086D01*
G01X481103Y149688D02*
Y350394D01*
G01X488977Y307086D02*
G03X481103I-3937J0D01*
G01Y346456D02*
G03X488977I3937J0D01*
G01Y370079D02*
G03X481103I-3937J0D01*
G01X488977Y346456D02*
Y370079D01*
G01X477166Y362205D02*
G03X481103Y366142I0J3937D01*
G01D02*
Y501099D01*
G01Y350394D02*
G03X477166Y354331I-3937J0D01*
G01D02*
X452028D01*
G01X481103Y409449D02*
G03X488977I3937J0D01*
G01D02*
Y498262D01*
G01X512599Y463013D02*
G03Y455139I0J-3937D01*
G01Y463013D02*
Y727913D01*
G01X492711Y499506D02*
G03X500788Y510711I-3734J11205D01*
G01X488977Y498262D02*
X492712Y499507D01*
G01X500788Y510711D02*
Y528658D01*
G01X483795Y504834D02*
G03X481103Y501099I1245J-3735D01*
G01X490221Y506976D02*
G03X492914Y510711I-1244J3735D01*
G01X483795Y504834D02*
X490222Y506976D01*
G01X492914Y510711D02*
Y528658D01*
G01X500788D02*
G03X492711Y539863I-11811J0D01*
G01X488977Y541108D02*
X492712Y539863D01*
G01X488977Y541108D02*
Y695669D01*
G01X481103Y538271D02*
G03X483795Y534535I3937J-1D01*
G01X492914Y528658D02*
G03X490221Y532393I-3937J0D01*
G01X483795Y534536D02*
X490222Y532393D01*
G01X481103Y538271D02*
Y738976D01*
G01X499107Y713716D02*
G03I-4291J0D01*
G01X492914Y742913D02*
G03X488977Y738976I0J-3937D01*
G01X512599Y727913D02*
G03X497599Y742913I-15000J0D01*
G01X488977Y695669D02*
G03X481103I-3937J0D01*
G01Y735039D02*
G03X488977I3937J0D01*
G01X492914Y742913D02*
X497599D01*
G01X488977Y735039D02*
Y738976D01*
G01X481103D02*
G03X477166Y742913I-3937J0D01*
G01D02*
X452028D01*
M02*
